# T6G (Grand Teton) — schematic netlist excerpt (pin names and nets, part order shuffled) for the footprints in the layout excerpt that follows; sources: Cadence DE-HDL packaged netlist, KiCad conversion of 04192023_DAF0TMB3IC0_F0TG_MB_C_brd_V02_OCP.brd

C29  Q_CAP  0.22UF 25V 10% X7R  pkg C0402  page 188 : A = SW_P3V3_EN_ISO_R ; B = GND
R483  Q_RES  0 5% CHIP  pkg 0402LF  page 27 : A = CPU0_XTRIG_L5 ; B = CPU0_XTRIG_R1_L5

(kicad_pcb
	(version 20260206)
	(generator "pcbnew")
	(generator_version "10.0")
	(general
		(thickness 1.6)
		(legacy_teardrops no)
	)
	(paper "A4")
	(title_block
		(title "04192023_DAF0TMB3IC0_F0TG_MB_C_brd_V02_OCP.brd")
		(comment 1 "Grand Teton / footprints 146-147 of 8354")
	)
	(layers
		(0 "F.Cu" signal "TOP")
		(4 "In1.Cu" signal "GND")
		(6 "In2.Cu" signal "IN1")
		(8 "In3.Cu" signal "GND1")
		(10 "In4.Cu" signal "IN2")
		(12 "In5.Cu" signal "GND2")
		(14 "In6.Cu" signal "IN3")
		(16 "In7.Cu" signal "GND3")
		(18 "In8.Cu" signal "VCC")
		(20 "In9.Cu" signal "VCC1")
		(22 "In10.Cu" signal "GND4")
		(24 "In11.Cu" signal "IN4")
		(26 "In12.Cu" signal "GND5")
		(28 "In13.Cu" signal "IN5")
		(30 "In14.Cu" signal "GND6")
		(32 "In15.Cu" signal "IN6")
		(34 "In16.Cu" signal "GND7")
		(2 "B.Cu" signal "BOTTOM")
		(9 "F.Adhes" user "F.Adhesive")
		(11 "B.Adhes" user "B.Adhesive")
		(13 "F.Paste" user "Package Geometry/Pastemask Top")
		(15 "B.Paste" user "Package Geometry/Pastemask Bottom")
		(5 "F.SilkS" user "Ref Des/Silkscreen Top")
		(7 "B.SilkS" user "Ref Des/Silkscreen Bottom")
		(1 "F.Mask" user "Board Geometry/Soldermask Top")
		(3 "B.Mask" user "Board Geometry/Soldermask Bottom")
		(17 "Dwgs.User" user "User.Drawings")
		(19 "Cmts.User" user "User.Comments")
		(21 "Eco1.User" user "User.Eco1")
		(23 "Eco2.User" user "User.Eco2")
		(25 "Edge.Cuts" user "Board Geometry/Outline")
		(27 "Margin" user)
		(31 "F.CrtYd" user "Package Geometry/Place Bound Top")
		(29 "B.CrtYd" user "Package Geometry/Place Bound Bottom")
		(35 "F.Fab" user "Ref Des/Assembly Top")
		(33 "B.Fab" user "Ref Des/Assembly Bottom")
	)
	(footprint ""
		(layer "F.Cu")
		(at 350.44761 -61.364876 180)
		(property "Reference" "R483"
			(at 0 0 180)
			(layer "F.SilkS")
			(hide yes)
			(effects
				(font
					(size 1.27 1.27)
				)
			)
		)
		(property "Value" ""
			(at 0 0 180)
			(layer "F.Fab")
			(effects
				(font
					(size 1.27 1.27)
				)
			)
		)
		(duplicate_pad_numbers_are_jumpers no)
		(fp_line
			(start 0.7874 0.4064)
			(end -0.7874 0.4064)
			(stroke
				(width 0.1524)
				(type default)
			)
			(layer "F.SilkS")
		)
		(fp_line
			(start 0.7874 -0.4064)
			(end 0.7874 0.4064)
			(stroke
				(width 0.1524)
				(type default)
			)
			(layer "F.SilkS")
		)
		(fp_line
			(start -0.7874 0.4064)
			(end -0.7874 -0.4064)
			(stroke
				(width 0.1524)
				(type default)
			)
			(layer "F.SilkS")
		)
		(fp_line
			(start -0.7874 -0.4064)
			(end 0.7874 -0.4064)
			(stroke
				(width 0.1524)
				(type default)
			)
			(layer "F.SilkS")
		)
		(fp_line
			(start 0.67945 0.3048)
			(end 0.120396 0.3048)
			(stroke
				(width 0.1)
				(type default)
			)
			(layer "F.Fab")
		)
		(fp_line
			(start 0.67945 -0.3048)
			(end 0.67945 0.3048)
			(stroke
				(width 0.1)
				(type default)
			)
			(layer "F.Fab")
		)
		(fp_line
			(start 0.12065 -0.2794)
			(end 0.12065 -0.3048)
			(stroke
				(width 0.1)
				(type default)
			)
			(layer "F.Fab")
		)
		(fp_line
			(start 0.12065 -0.3048)
			(end 0.67945 -0.3048)
			(stroke
				(width 0.1)
				(type default)
			)
			(layer "F.Fab")
		)
		(fp_line
			(start 0.120396 0.3048)
			(end 0.120396 0.2794)
			(stroke
				(width 0.1)
				(type default)
			)
			(layer "F.Fab")
		)
		(fp_line
			(start 0.120396 0.2794)
			(end -0.12065 0.2794)
			(stroke
				(width 0.1)
				(type default)
			)
			(layer "F.Fab")
		)
		(fp_line
			(start -0.12065 0.3048)
			(end -0.67945 0.3048)
			(stroke
				(width 0.1)
				(type default)
			)
			(layer "F.Fab")
		)
		(fp_line
			(start -0.12065 0.2794)
			(end -0.12065 0.3048)
			(stroke
				(width 0.1)
				(type default)
			)
			(layer "F.Fab")
		)
		(fp_line
			(start -0.12065 -0.2794)
			(end 0.12065 -0.2794)
			(stroke
				(width 0.1)
				(type default)
			)
			(layer "F.Fab")
		)
		(fp_line
			(start -0.12065 -0.305054)
			(end -0.12065 -0.2794)
			(stroke
				(width 0.1)
				(type default)
			)
			(layer "F.Fab")
		)
		(fp_line
			(start -0.67945 0.3048)
			(end -0.67945 -0.305054)
			(stroke
				(width 0.1)
				(type default)
			)
			(layer "F.Fab")
		)
		(fp_line
			(start -0.67945 -0.305054)
			(end -0.12065 -0.305054)
			(stroke
				(width 0.1)
				(type default)
			)
			(layer "F.Fab")
		)
		(pad "1" smd circle
			(at -0.40005 0 180)
			(size 0 0)
			(layers "F.Cu" "F.Mask" "F.Paste")
			(net "CPU0_XTRIG_L5")
		)
		(pad "2" smd circle
			(at 0.40005 0 180)
			(size 0 0)
			(layers "F.Cu" "F.Mask" "F.Paste")
			(net "CPU0_XTRIG_R1_L5")
		)
	)
	(footprint ""
		(layer "F.Cu")
		(at 209.423 -129.54 90)
		(property "Reference" "C29"
			(at 0 0 90)
			(layer "F.SilkS")
			(hide yes)
			(effects
				(font
					(size 1.27 1.27)
				)
			)
		)
		(property "Value" ""
			(at 0 0 90)
			(layer "F.Fab")
			(effects
				(font
					(size 1.27 1.27)
				)
			)
		)
		(duplicate_pad_numbers_are_jumpers no)
		(fp_line
			(start 0.7874 -0.4064)
			(end 0.7874 0.4064)
			(stroke
				(width 0.1524)
				(type default)
			)
			(layer "F.SilkS")
		)
		(fp_line
			(start -0.7874 -0.4064)
			(end 0.7874 -0.4064)
			(stroke
				(width 0.1524)
				(type default)
			)
			(layer "F.SilkS")
		)
		(fp_line
			(start 0.7874 0.4064)
			(end -0.7874 0.4064)
			(stroke
				(width 0.1524)
				(type default)
			)
			(layer "F.SilkS")
		)
		(fp_line
			(start -0.7874 0.4064)
			(end -0.7874 -0.4064)
			(stroke
				(width 0.1524)
				(type default)
			)
			(layer "F.SilkS")
		)
		(fp_line
			(start -0.12065 -0.305054)
			(end -0.12065 -0.2794)
			(stroke
				(width 0.1)
				(type default)
			)
			(layer "F.Fab")
		)
		(fp_line
			(start -0.67945 -0.305054)
			(end -0.12065 -0.305054)
			(stroke
				(width 0.1)
				(type default)
			)
			(layer "F.Fab")
		)
		(fp_line
			(start 0.67945 -0.3048)
			(end 0.67945 0.3048)
			(stroke
				(width 0.1)
				(type default)
			)
			(layer "F.Fab")
		)
		(fp_line
			(start 0.12065 -0.3048)
			(end 0.67945 -0.3048)
			(stroke
				(width 0.1)
				(type default)
			)
			(layer "F.Fab")
		)
		(fp_line
			(start 0.12065 -0.2794)
			(end 0.12065 -0.3048)
			(stroke
				(width 0.1)
				(type default)
			)
			(layer "F.Fab")
		)
		(fp_line
			(start -0.12065 -0.2794)
			(end 0.12065 -0.2794)
			(stroke
				(width 0.1)
				(type default)
			)
			(layer "F.Fab")
		)
		(fp_line
			(start 0.120396 0.2794)
			(end -0.12065 0.2794)
			(stroke
				(width 0.1)
				(type default)
			)
			(layer "F.Fab")
		)
		(fp_line
			(start -0.12065 0.2794)
			(end -0.12065 0.3048)
			(stroke
				(width 0.1)
				(type default)
			)
			(layer "F.Fab")
		)
		(fp_line
			(start 0.67945 0.3048)
			(end 0.120396 0.3048)
			(stroke
				(width 0.1)
				(type default)
			)
			(layer "F.Fab")
		)
		(fp_line
			(start 0.120396 0.3048)
			(end 0.120396 0.2794)
			(stroke
				(width 0.1)
				(type default)
			)
			(layer "F.Fab")
		)
		(fp_line
			(start -0.12065 0.3048)
			(end -0.67945 0.3048)
			(stroke
				(width 0.1)
				(type default)
			)
			(layer "F.Fab")
		)
		(fp_line
			(start -0.67945 0.3048)
			(end -0.67945 -0.305054)
			(stroke
				(width 0.1)
				(type default)
			)
			(layer "F.Fab")
		)
		(pad "1" smd circle
			(at -0.40005 0 90)
			(size 0 0)
			(layers "F.Cu" "F.Mask" "F.Paste")
			(net "SW_P3V3_EN_ISO_R")
		)
		(pad "2" smd circle
			(at 0.40005 0 90)
			(size 0 0)
			(layers "F.Cu" "F.Mask" "F.Paste")
			(net "GND")
		)
	)
)
